(kicad_pcb
	(version 20260206)
	(generator "pcbnew")
	(generator_version "10.0")
	(general
		(thickness 1.6)
		(legacy_teardrops no)
	)
	(paper "A4")
	(title_block
		(title "panther-plus-userver — 13130-1b_20150205.brd")
		(comment 1 "Honey Badger (Wiwynn) / footprints 380-387 of 1509")
	)
	(layers
		(0 "F.Cu" signal "TOP")
		(4 "In1.Cu" signal "L2")
		(6 "In2.Cu" signal "L3")
		(8 "In3.Cu" signal "L4")
		(10 "In4.Cu" signal "L5")
		(12 "In5.Cu" signal "L6")
		(14 "In6.Cu" signal "L7")
		(16 "In7.Cu" signal "L8")
		(18 "In8.Cu" signal "L9")
		(20 "In9.Cu" signal "L10")
		(22 "In10.Cu" signal "L11")
		(2 "B.Cu" signal "BOTTOM")
		(9 "F.Adhes" user "F.Adhesive")
		(11 "B.Adhes" user "B.Adhesive")
		(13 "F.Paste" user "Package Geometry/Pastemask Top")
		(15 "B.Paste" user "Package Geometry/Pastemask Bottom")
		(5 "F.SilkS" user "Ref Des/Silkscreen Top")
		(7 "B.SilkS" user "Ref Des/Silkscreen Bottom")
		(1 "F.Mask" user "Board Geometry/Soldermask Top")
		(3 "B.Mask" user "Board Geometry/Soldermask Bottom")
		(17 "Dwgs.User" user "User.Drawings")
		(19 "Cmts.User" user "User.Comments")
		(21 "Eco1.User" user "User.Eco1")
		(23 "Eco2.User" user "User.Eco2")
		(25 "Edge.Cuts" user "Board Geometry/Outline")
		(27 "Margin" user)
		(31 "F.CrtYd" user "Package Geometry/Place Bound Top")
		(29 "B.CrtYd" user "Package Geometry/Place Bound Bottom")
		(35 "F.Fab" user "Ref Des/Assembly Top")
		(33 "B.Fab" user "Ref Des/Assembly Bottom")
	)
	(footprint ""
		(layer "F.Cu")
		(at 173.355 -46.482 90)
		(property "Reference" "R191"
			(at 0 0 90)
			(layer "F.SilkS")
			(hide yes)
			(effects
				(font
					(size 1.27 1.27)
				)
			)
		)
		(property "Value" "0R2J-2-GP"
			(at 0.064008 -3.993896 90)
			(unlocked yes)
			(layer "F.Fab")
			(hide yes)
			(effects
				(font
					(size 1.016 1.016)
					(thickness 0.1524)
				)
			)
		)
		(property "Device Type" "R402H16"
			(at 0.064008 -5.517896 90)
			(unlocked yes)
			(layer "F.Fab")
			(hide yes)
			(effects
				(font
					(size 1.016 1.016)
					(thickness 0.1524)
				)
			)
		)
		(duplicate_pad_numbers_are_jumpers no)
		(fp_rect
			(start -0.381 0.8382)
			(end 0.381 -0.8382)
			(stroke
				(width 0)
				(type default)
			)
			(fill no)
			(layer "F.CrtYd")
		)
		(fp_rect
			(start -0.381 0.8382)
			(end 0.381 -0.8382)
			(stroke
				(width 0)
				(type default)
			)
			(fill no)
			(layer "F.Fab")
		)
		(pad "1" smd custom
			(at 0 -0.4318 90)
			(size 0.127 0.127)
			(layers "F.Cu" "F.Mask" "F.Paste")
			(net "EEPROM_DATA")
			(options
				(clearance outline)
				(anchor circle)
			)
			(primitives
				(gr_poly
					(pts
						(arc
							(start -0.2032 -0.2794)
							(mid -0.239121 -0.264521)
							(end -0.254 -0.2286)
						)
						(arc
							(start -0.254 0.2286)
							(mid -0.239121 0.264521)
							(end -0.2032 0.2794)
						)
						(arc
							(start 0.2032 0.2794)
							(mid 0.239121 0.264521)
							(end 0.254 0.2286)
						)
						(arc
							(start 0.254 -0.2286)
							(mid 0.239121 -0.264521)
							(end 0.2032 -0.2794)
						)
					)
					(width 0)
					(fill yes)
				)
			)
		)
		(pad "2" smd custom
			(at 0 0.4318 90)
			(size 0.127 0.127)
			(layers "F.Cu" "F.Mask" "F.Paste")
			(net "BMC_I2C_DATA")
			(options
				(clearance outline)
				(anchor circle)
			)
			(primitives
				(gr_poly
					(pts
						(arc
							(start -0.2032 -0.2794)
							(mid -0.239121 -0.264521)
							(end -0.254 -0.2286)
						)
						(arc
							(start -0.254 0.2286)
							(mid -0.239121 0.264521)
							(end -0.2032 0.2794)
						)
						(arc
							(start 0.2032 0.2794)
							(mid 0.239121 0.264521)
							(end 0.254 0.2286)
						)
						(arc
							(start 0.254 -0.2286)
							(mid 0.239121 -0.264521)
							(end 0.2032 -0.2794)
						)
					)
					(width 0)
					(fill yes)
				)
			)
		)
	)
	(footprint ""
		(layer "F.Cu")
		(at 69.596 -30.734 -90)
		(property "Reference" "R403"
			(at 0 0 270)
			(layer "F.SilkS")
			(hide yes)
			(effects
				(font
					(size 1.27 1.27)
				)
			)
		)
		(property "Value" "1KR2F-3-GP"
			(at 1.7907 -1.1176 270)
			(unlocked yes)
			(layer "F.Fab")
			(hide yes)
			(effects
				(font
					(size 1.016 1.016)
					(thickness 0.1524)
				)
			)
		)
		(property "Device Type" "R402H16"
			(at 1.7907 -2.6416 270)
			(unlocked yes)
			(layer "F.Fab")
			(hide yes)
			(effects
				(font
					(size 1.016 1.016)
					(thickness 0.1524)
				)
			)
		)
		(duplicate_pad_numbers_are_jumpers no)
		(fp_rect
			(start -0.381 0.8382)
			(end 0.381 -0.8382)
			(stroke
				(width 0)
				(type default)
			)
			(fill no)
			(layer "F.CrtYd")
		)
		(fp_rect
			(start -0.381 0.8382)
			(end 0.381 -0.8382)
			(stroke
				(width 0)
				(type default)
			)
			(fill no)
			(layer "F.Fab")
		)
		(pad "1" smd custom
			(at 0 -0.4318 270)
			(size 0.127 0.127)
			(layers "F.Cu" "F.Mask" "F.Paste")
			(net "BD_ID_2")
			(options
				(clearance outline)
				(anchor circle)
			)
			(primitives
				(gr_poly
					(pts
						(arc
							(start -0.2032 -0.2794)
							(mid -0.239121 -0.264521)
							(end -0.254 -0.2286)
						)
						(arc
							(start -0.254 0.2286)
							(mid -0.239121 0.264521)
							(end -0.2032 0.2794)
						)
						(arc
							(start 0.2032 0.2794)
							(mid 0.239121 0.264521)
							(end 0.254 0.2286)
						)
						(arc
							(start 0.254 -0.2286)
							(mid 0.239121 -0.264521)
							(end 0.2032 -0.2794)
						)
					)
					(width 0)
					(fill yes)
				)
			)
		)
		(pad "2" smd custom
			(at 0 0.4318 270)
			(size 0.127 0.127)
			(layers "F.Cu" "F.Mask" "F.Paste")
			(net "GND")
			(options
				(clearance outline)
				(anchor circle)
			)
			(primitives
				(gr_poly
					(pts
						(arc
							(start -0.2032 -0.2794)
							(mid -0.239121 -0.264521)
							(end -0.254 -0.2286)
						)
						(arc
							(start -0.254 0.2286)
							(mid -0.239121 0.264521)
							(end -0.2032 0.2794)
						)
						(arc
							(start 0.2032 0.2794)
							(mid 0.239121 0.264521)
							(end 0.254 0.2286)
						)
						(arc
							(start 0.254 -0.2286)
							(mid 0.239121 -0.264521)
							(end 0.2032 -0.2794)
						)
					)
					(width 0)
					(fill yes)
				)
			)
		)
	)
	(footprint ""
		(layer "F.Cu")
		(at 49.149 -16.0782 180)
		(property "Reference" "R325"
			(at 0 0 180)
			(layer "F.SilkS")
			(hide yes)
			(effects
				(font
					(size 1.27 1.27)
				)
			)
		)
		(property "Value" "4K7R2F-GP"
			(at 0.064008 -3.993896 180)
			(unlocked yes)
			(layer "F.Fab")
			(hide yes)
			(effects
				(font
					(size 1.016 1.016)
					(thickness 0.1524)
				)
			)
		)
		(property "Device Type" "R402H16"
			(at 0.064008 -5.517896 180)
			(unlocked yes)
			(layer "F.Fab")
			(hide yes)
			(effects
				(font
					(size 1.016 1.016)
					(thickness 0.1524)
				)
			)
		)
		(duplicate_pad_numbers_are_jumpers no)
		(fp_rect
			(start -0.381 0.8382)
			(end 0.381 -0.8382)
			(stroke
				(width 0)
				(type default)
			)
			(fill no)
			(layer "F.CrtYd")
		)
		(fp_rect
			(start -0.381 0.8382)
			(end 0.381 -0.8382)
			(stroke
				(width 0)
				(type default)
			)
			(fill no)
			(layer "F.Fab")
		)
		(pad "1" smd custom
			(at 0 -0.4318 180)
			(size 0.127 0.127)
			(layers "F.Cu" "F.Mask" "F.Paste")
			(net "P3V3")
			(options
				(clearance outline)
				(anchor circle)
			)
			(primitives
				(gr_poly
					(pts
						(arc
							(start -0.2032 -0.2794)
							(mid -0.239121 -0.264521)
							(end -0.254 -0.2286)
						)
						(arc
							(start -0.254 0.2286)
							(mid -0.239121 0.264521)
							(end -0.2032 0.2794)
						)
						(arc
							(start 0.2032 0.2794)
							(mid 0.239121 0.264521)
							(end 0.254 0.2286)
						)
						(arc
							(start 0.254 -0.2286)
							(mid 0.239121 -0.264521)
							(end 0.2032 -0.2794)
						)
					)
					(width 0)
					(fill yes)
				)
			)
		)
		(pad "2" smd custom
			(at 0 0.4318 180)
			(size 0.127 0.127)
			(layers "F.Cu" "F.Mask" "F.Paste")
			(net "CLKBUFF_OE0#")
			(options
				(clearance outline)
				(anchor circle)
			)
			(primitives
				(gr_poly
					(pts
						(arc
							(start -0.2032 -0.2794)
							(mid -0.239121 -0.264521)
							(end -0.254 -0.2286)
						)
						(arc
							(start -0.254 0.2286)
							(mid -0.239121 0.264521)
							(end -0.2032 0.2794)
						)
						(arc
							(start 0.2032 0.2794)
							(mid 0.239121 0.264521)
							(end 0.254 0.2286)
						)
						(arc
							(start 0.254 -0.2286)
							(mid 0.239121 -0.264521)
							(end 0.2032 -0.2794)
						)
					)
					(width 0)
					(fill yes)
				)
			)
		)
	)
	(footprint ""
		(layer "F.Cu")
		(at 158.115 -20.32)
		(property "Reference" "R414"
			(at 0 0 0)
			(layer "F.SilkS")
			(hide yes)
			(effects
				(font
					(size 1.27 1.27)
				)
			)
		)
		(property "Value" "0R2J-2-GP"
			(at 1.7907 -1.1176 0)
			(unlocked yes)
			(layer "F.Fab")
			(hide yes)
			(effects
				(font
					(size 1.016 1.016)
					(thickness 0.1524)
				)
			)
		)
		(property "Device Type" "R402H16"
			(at 1.7907 -2.6416 0)
			(unlocked yes)
			(layer "F.Fab")
			(hide yes)
			(effects
				(font
					(size 1.016 1.016)
					(thickness 0.1524)
				)
			)
		)
		(duplicate_pad_numbers_are_jumpers no)
		(fp_rect
			(start -0.381 0.8382)
			(end 0.381 -0.8382)
			(stroke
				(width 0)
				(type default)
			)
			(fill no)
			(layer "F.CrtYd")
		)
		(fp_rect
			(start -0.381 0.8382)
			(end 0.381 -0.8382)
			(stroke
				(width 0)
				(type default)
			)
			(fill no)
			(layer "F.Fab")
		)
		(pad "1" smd custom
			(at 0 -0.4318)
			(size 0.127 0.127)
			(layers "F.Cu" "F.Mask" "F.Paste")
			(net "DISABLE")
			(options
				(clearance outline)
				(anchor circle)
			)
			(primitives
				(gr_poly
					(pts
						(arc
							(start -0.2032 -0.2794)
							(mid -0.239121 -0.264521)
							(end -0.254 -0.2286)
						)
						(arc
							(start -0.254 0.2286)
							(mid -0.239121 0.264521)
							(end -0.2032 0.2794)
						)
						(arc
							(start 0.2032 0.2794)
							(mid 0.239121 0.264521)
							(end 0.254 0.2286)
						)
						(arc
							(start 0.254 -0.2286)
							(mid 0.239121 -0.264521)
							(end 0.2032 -0.2794)
						)
					)
					(width 0)
					(fill yes)
				)
			)
		)
		(pad "2" smd custom
			(at 0 0.4318)
			(size 0.127 0.127)
			(layers "F.Cu" "F.Mask" "F.Paste")
			(net "CPU_FPGA_DISABLE")
			(options
				(clearance outline)
				(anchor circle)
			)
			(primitives
				(gr_poly
					(pts
						(arc
							(start -0.2032 -0.2794)
							(mid -0.239121 -0.264521)
							(end -0.254 -0.2286)
						)
						(arc
							(start -0.254 0.2286)
							(mid -0.239121 0.264521)
							(end -0.2032 0.2794)
						)
						(arc
							(start 0.2032 0.2794)
							(mid 0.239121 0.264521)
							(end 0.254 0.2286)
						)
						(arc
							(start 0.254 -0.2286)
							(mid 0.239121 -0.264521)
							(end 0.2032 -0.2794)
						)
					)
					(width 0)
					(fill yes)
				)
			)
		)
	)
	(footprint ""
		(layer "F.Cu")
		(at 145.3134 -49.9364 180)
		(property "Reference" "TP38"
			(at 0 0 180)
			(layer "F.SilkS")
			(hide yes)
			(effects
				(font
					(size 1.27 1.27)
				)
			)
		)
		(property "Value" "TPAD32-GP"
			(at 0 -3.166364 180)
			(unlocked yes)
			(layer "F.Fab")
			(hide yes)
			(effects
				(font
					(size 1.016 1.016)
					(thickness 0.1524)
				)
			)
		)
		(property "Device Type" "TPAD32"
			(at 0 -4.690618 180)
			(unlocked yes)
			(layer "F.Fab")
			(hide yes)
			(effects
				(font
					(size 1.016 1.016)
					(thickness 0.1524)
				)
			)
		)
		(duplicate_pad_numbers_are_jumpers no)
		(fp_poly
			(pts
				(arc
					(start -0.7112 0)
					(mid 0.7112 0)
					(end -0.7112 0)
				)
			)
			(stroke
				(width 0)
				(type default)
			)
			(fill no)
			(layer "F.CrtYd")
		)
		(fp_poly
			(pts
				(arc
					(start -0.7112 0)
					(mid 0.7112 0)
					(end -0.7112 0)
				)
			)
			(stroke
				(width 0)
				(type default)
			)
			(fill no)
			(layer "F.Fab")
		)
		(pad "1" smd circle
			(at 0 0 180)
			(size 0.8128 0.8128)
			(layers "F.Cu" "F.Mask" "F.Paste")
			(net "C_CSO#")
		)
	)
	(footprint ""
		(layer "F.Cu")
		(at 54.356 -44.0944 180)
		(property "Reference" "C16"
			(at 0 0 180)
			(layer "F.SilkS")
			(hide yes)
			(effects
				(font
					(size 1.27 1.27)
				)
			)
		)
		(property "Value" "SC1U25V3KX-GP"
			(at -0.0254 -2.0193 180)
			(unlocked yes)
			(layer "F.Fab")
			(hide yes)
			(effects
				(font
					(size 1.016 1.016)
					(thickness 0.1524)
				)
			)
		)
		(property "Device Type" "C603H36"
			(at -0.0254 -3.5433 180)
			(unlocked yes)
			(layer "F.Fab")
			(hide yes)
			(effects
				(font
					(size 1.016 1.016)
					(thickness 0.1524)
				)
			)
		)
		(duplicate_pad_numbers_are_jumpers no)
		(fp_line
			(start -0.4064 0)
			(end 0.4064 0)
			(stroke
				(width 0.2286)
				(type default)
			)
			(layer "F.SilkS")
		)
		(fp_rect
			(start -0.635 1.1811)
			(end 0.635 -1.1811)
			(stroke
				(width 0)
				(type default)
			)
			(fill no)
			(layer "F.CrtYd")
		)
		(fp_rect
			(start -0.635 1.1811)
			(end 0.635 -1.1811)
			(stroke
				(width 0)
				(type default)
			)
			(fill no)
			(layer "F.Fab")
		)
		(pad "1" smd custom
			(at 0 -0.6604 180)
			(size 0.19685 0.19685)
			(layers "F.Cu" "F.Mask" "F.Paste")
			(net "SW_P3V3_CPU_EN_LV_D")
			(options
				(clearance outline)
				(anchor circle)
			)
			(primitives
				(gr_poly
					(pts
						(arc
							(start 0.508 -0.2921)
							(mid 0.478242 -0.363942)
							(end 0.4064 -0.3937)
						)
						(arc
							(start -0.4064 -0.3937)
							(mid -0.478242 -0.363942)
							(end -0.508 -0.2921)
						)
						(arc
							(start -0.508 0.2921)
							(mid -0.478242 0.363942)
							(end -0.4064 0.3937)
						)
						(arc
							(start 0.4064 0.3937)
							(mid 0.478242 0.363942)
							(end 0.508 0.2921)
						)
					)
					(width 0)
					(fill yes)
				)
			)
		)
		(pad "2" smd custom
			(at 0 0.6604 180)
			(size 0.19685 0.19685)
			(layers "F.Cu" "F.Mask" "F.Paste")
			(net "GND")
			(options
				(clearance outline)
				(anchor circle)
			)
			(primitives
				(gr_poly
					(pts
						(arc
							(start 0.508 -0.2921)
							(mid 0.478242 -0.363942)
							(end 0.4064 -0.3937)
						)
						(arc
							(start -0.4064 -0.3937)
							(mid -0.478242 -0.363942)
							(end -0.508 -0.2921)
						)
						(arc
							(start -0.508 0.2921)
							(mid -0.478242 0.363942)
							(end -0.4064 0.3937)
						)
						(arc
							(start 0.4064 0.3937)
							(mid 0.478242 0.363942)
							(end 0.508 0.2921)
						)
					)
					(width 0)
					(fill yes)
				)
			)
		)
	)
	(footprint ""
		(layer "F.Cu")
		(at 19.7358 -64.7192 180)
		(property "Reference" "PR20"
			(at 0 0 180)
			(layer "F.SilkS")
			(hide yes)
			(effects
				(font
					(size 1.27 1.27)
				)
			)
		)
		(property "Value" "0R2J-2-GP"
			(at 1.7907 -1.1176 180)
			(unlocked yes)
			(layer "F.Fab")
			(hide yes)
			(effects
				(font
					(size 1.016 1.016)
					(thickness 0.1524)
				)
			)
		)
		(property "Device Type" "R402H16"
			(at 1.7907 -2.6416 180)
			(unlocked yes)
			(layer "F.Fab")
			(hide yes)
			(effects
				(font
					(size 1.016 1.016)
					(thickness 0.1524)
				)
			)
		)
		(duplicate_pad_numbers_are_jumpers no)
		(fp_rect
			(start -0.381 0.8382)
			(end 0.381 -0.8382)
			(stroke
				(width 0)
				(type default)
			)
			(fill no)
			(layer "F.CrtYd")
		)
		(fp_rect
			(start -0.381 0.8382)
			(end 0.381 -0.8382)
			(stroke
				(width 0)
				(type default)
			)
			(fill no)
			(layer "F.Fab")
		)
		(pad "1" smd custom
			(at 0 -0.4318 180)
			(size 0.127 0.127)
			(layers "F.Cu" "F.Mask" "F.Paste")
			(net "VR_PVNN_VSEN")
			(options
				(clearance outline)
				(anchor circle)
			)
			(primitives
				(gr_poly
					(pts
						(arc
							(start -0.2032 -0.2794)
							(mid -0.239121 -0.264521)
							(end -0.254 -0.2286)
						)
						(arc
							(start -0.254 0.2286)
							(mid -0.239121 0.264521)
							(end -0.2032 0.2794)
						)
						(arc
							(start 0.2032 0.2794)
							(mid 0.239121 0.264521)
							(end 0.254 0.2286)
						)
						(arc
							(start 0.254 -0.2286)
							(mid 0.239121 -0.264521)
							(end 0.2032 -0.2794)
						)
					)
					(width 0)
					(fill yes)
				)
			)
		)
		(pad "2" smd custom
			(at 0 0.4318 180)
			(size 0.127 0.127)
			(layers "F.Cu" "F.Mask" "F.Paste")
			(net "VR_PVNN_VSEN_R")
			(options
				(clearance outline)
				(anchor circle)
			)
			(primitives
				(gr_poly
					(pts
						(arc
							(start -0.2032 -0.2794)
							(mid -0.239121 -0.264521)
							(end -0.254 -0.2286)
						)
						(arc
							(start -0.254 0.2286)
							(mid -0.239121 0.264521)
							(end -0.2032 0.2794)
						)
						(arc
							(start 0.2032 0.2794)
							(mid 0.239121 0.264521)
							(end 0.254 0.2286)
						)
						(arc
							(start 0.254 -0.2286)
							(mid 0.239121 -0.264521)
							(end 0.2032 -0.2794)
						)
					)
					(width 0)
					(fill yes)
				)
			)
		)
	)
	(footprint ""
		(layer "F.Cu")
		(at 185.039 -42.926 -90)
		(property "Reference" "R223"
			(at 0 0 270)
			(layer "F.SilkS")
			(hide yes)
			(effects
				(font
					(size 1.27 1.27)
				)
			)
		)
		(property "Value" "0R2J-2-GP"
			(at 0.064008 -3.993896 270)
			(unlocked yes)
			(layer "F.Fab")
			(hide yes)
			(effects
				(font
					(size 1.016 1.016)
					(thickness 0.1524)
				)
			)
		)
		(property "Device Type" "R402H16"
			(at 0.064008 -5.517896 270)
			(unlocked yes)
			(layer "F.Fab")
			(hide yes)
			(effects
				(font
					(size 1.016 1.016)
					(thickness 0.1524)
				)
			)
		)
		(duplicate_pad_numbers_are_jumpers no)
		(fp_rect
			(start -0.381 0.8382)
			(end 0.381 -0.8382)
			(stroke
				(width 0)
				(type default)
			)
			(fill no)
			(layer "F.CrtYd")
		)
		(fp_rect
			(start -0.381 0.8382)
			(end 0.381 -0.8382)
			(stroke
				(width 0)
				(type default)
			)
			(fill no)
			(layer "F.Fab")
		)
		(pad "1" smd custom
			(at 0 -0.4318 270)
			(size 0.127 0.127)
			(layers "F.Cu" "F.Mask" "F.Paste")
			(net "PV_VDDR_VREF_B")
			(options
				(clearance outline)
				(anchor circle)
			)
			(primitives
				(gr_poly
					(pts
						(arc
							(start -0.2032 -0.2794)
							(mid -0.239121 -0.264521)
							(end -0.254 -0.2286)
						)
						(arc
							(start -0.254 0.2286)
							(mid -0.239121 0.264521)
							(end -0.2032 0.2794)
						)
						(arc
							(start 0.2032 0.2794)
							(mid 0.239121 0.264521)
							(end 0.254 0.2286)
						)
						(arc
							(start 0.254 -0.2286)
							(mid 0.239121 -0.264521)
							(end 0.2032 -0.2794)
						)
					)
					(width 0)
					(fill yes)
				)
			)
		)
		(pad "2" smd custom
			(at 0 0.4318 270)
			(size 0.127 0.127)
			(layers "F.Cu" "F.Mask" "F.Paste")
			(net "DDR3_M_B_VREF_DQ1")
			(options
				(clearance outline)
				(anchor circle)
			)
			(primitives
				(gr_poly
					(pts
						(arc
							(start -0.2032 -0.2794)
							(mid -0.239121 -0.264521)
							(end -0.254 -0.2286)
						)
						(arc
							(start -0.254 0.2286)
							(mid -0.239121 0.264521)
							(end -0.2032 0.2794)
						)
						(arc
							(start 0.2032 0.2794)
							(mid 0.239121 0.264521)
							(end 0.254 0.2286)
						)
						(arc
							(start 0.254 -0.2286)
							(mid 0.239121 -0.264521)
							(end 0.2032 -0.2794)
						)
					)
					(width 0)
					(fill yes)
				)
			)
		)
	)
)
